(kicad_pcb
	(version 20260206)
	(generator "pcbnew")
	(generator_version "10.0")
	(general
		(thickness 1.6)
		(legacy_teardrops no)
	)
	(paper "A4")
	(title_block
		(title "04192023_DAF0TMB3IC0_F0TG_MB_C_brd_V02_OCP.brd")
		(comment 1 "Grand Teton / footprints 7761-7767 of 8354")
	)
	(layers
		(0 "F.Cu" signal "TOP")
		(4 "In1.Cu" signal "GND")
		(6 "In2.Cu" signal "IN1")
		(8 "In3.Cu" signal "GND1")
		(10 "In4.Cu" signal "IN2")
		(12 "In5.Cu" signal "GND2")
		(14 "In6.Cu" signal "IN3")
		(16 "In7.Cu" signal "GND3")
		(18 "In8.Cu" signal "VCC")
		(20 "In9.Cu" signal "VCC1")
		(22 "In10.Cu" signal "GND4")
		(24 "In11.Cu" signal "IN4")
		(26 "In12.Cu" signal "GND5")
		(28 "In13.Cu" signal "IN5")
		(30 "In14.Cu" signal "GND6")
		(32 "In15.Cu" signal "IN6")
		(34 "In16.Cu" signal "GND7")
		(2 "B.Cu" signal "BOTTOM")
		(9 "F.Adhes" user "F.Adhesive")
		(11 "B.Adhes" user "B.Adhesive")
		(13 "F.Paste" user "Package Geometry/Pastemask Top")
		(15 "B.Paste" user "Package Geometry/Pastemask Bottom")
		(5 "F.SilkS" user "Ref Des/Silkscreen Top")
		(7 "B.SilkS" user "Ref Des/Silkscreen Bottom")
		(1 "F.Mask" user "Board Geometry/Soldermask Top")
		(3 "B.Mask" user "Board Geometry/Soldermask Bottom")
		(17 "Dwgs.User" user "User.Drawings")
		(19 "Cmts.User" user "User.Comments")
		(21 "Eco1.User" user "User.Eco1")
		(23 "Eco2.User" user "User.Eco2")
		(25 "Edge.Cuts" user "Board Geometry/Outline")
		(27 "Margin" user)
		(31 "F.CrtYd" user "Package Geometry/Place Bound Top")
		(29 "B.CrtYd" user "Package Geometry/Place Bound Bottom")
		(35 "F.Fab" user "Ref Des/Assembly Top")
		(33 "B.Fab" user "Ref Des/Assembly Bottom")
	)
	(footprint ""
		(layer "B.Cu")
		(at 361.54106 -186.225942 90)
		(property "Reference" "PC499_2"
			(at 0 0 90)
			(layer "B.SilkS")
			(hide yes)
			(effects
				(font
					(size 1.27 1.27)
				)
				(justify mirror)
			)
		)
		(property "Value" ""
			(at 0 0 90)
			(layer "B.Fab")
			(effects
				(font
					(size 1.27 1.27)
				)
				(justify mirror)
			)
		)
		(duplicate_pad_numbers_are_jumpers no)
		(fp_line
			(start 1.524 -0.762)
			(end -1.524 -0.762)
			(stroke
				(width 0.1524)
				(type default)
			)
			(layer "B.SilkS")
		)
		(fp_line
			(start -1.524 -0.762)
			(end -1.524 0.762)
			(stroke
				(width 0.1524)
				(type default)
			)
			(layer "B.SilkS")
		)
		(fp_line
			(start 1.524 0.762)
			(end 1.524 -0.762)
			(stroke
				(width 0.1524)
				(type default)
			)
			(layer "B.SilkS")
		)
		(fp_line
			(start -1.524 0.762)
			(end 1.524 0.762)
			(stroke
				(width 0.1524)
				(type default)
			)
			(layer "B.SilkS")
		)
		(fp_line
			(start 1.1049 -0.724916)
			(end 1.1049 0.724916)
			(stroke
				(width 0.1)
				(type default)
			)
			(layer "B.Fab")
		)
		(fp_line
			(start -1.1049 -0.724916)
			(end 1.1049 -0.724916)
			(stroke
				(width 0.1)
				(type default)
			)
			(layer "B.Fab")
		)
		(fp_line
			(start 1.1049 0.724916)
			(end -1.1049 0.724916)
			(stroke
				(width 0.1)
				(type default)
			)
			(layer "B.Fab")
		)
		(fp_line
			(start -1.1049 0.724916)
			(end -1.1049 -0.724916)
			(stroke
				(width 0.1)
				(type default)
			)
			(layer "B.Fab")
		)
		(pad "1" smd rect
			(at 0.889 0 90)
			(size 1.016 1.27)
			(layers "B.Cu" "B.Mask" "B.Paste")
			(net "PVDDCR_CPU0_P0")
		)
		(pad "2" smd rect
			(at -0.889 0 90)
			(size 1.016 1.27)
			(layers "B.Cu" "B.Mask" "B.Paste")
			(net "GND")
		)
	)
	(footprint ""
		(layer "B.Cu")
		(at 167.531034 -244.085364)
		(property "Reference" "R506"
			(at 0 0 0)
			(layer "B.SilkS")
			(hide yes)
			(effects
				(font
					(size 1.27 1.27)
				)
				(justify mirror)
			)
		)
		(property "Value" ""
			(at 0 0 0)
			(layer "B.Fab")
			(effects
				(font
					(size 1.27 1.27)
				)
				(justify mirror)
			)
		)
		(duplicate_pad_numbers_are_jumpers no)
		(fp_line
			(start -0.7874 -0.4064)
			(end -0.7874 0.4064)
			(stroke
				(width 0.1524)
				(type default)
			)
			(layer "B.SilkS")
		)
		(fp_line
			(start -0.7874 0.4064)
			(end 0.7874 0.4064)
			(stroke
				(width 0.1524)
				(type default)
			)
			(layer "B.SilkS")
		)
		(fp_line
			(start 0.7874 -0.4064)
			(end -0.7874 -0.4064)
			(stroke
				(width 0.1524)
				(type default)
			)
			(layer "B.SilkS")
		)
		(fp_line
			(start 0.7874 0.4064)
			(end 0.7874 -0.4064)
			(stroke
				(width 0.1524)
				(type default)
			)
			(layer "B.SilkS")
		)
		(fp_line
			(start -0.67945 -0.3048)
			(end -0.67945 0.3048)
			(stroke
				(width 0.1)
				(type default)
			)
			(layer "B.Fab")
		)
		(fp_line
			(start -0.67945 0.3048)
			(end -0.120396 0.3048)
			(stroke
				(width 0.1)
				(type default)
			)
			(layer "B.Fab")
		)
		(fp_line
			(start -0.12065 -0.3048)
			(end -0.67945 -0.3048)
			(stroke
				(width 0.1)
				(type default)
			)
			(layer "B.Fab")
		)
		(fp_line
			(start -0.12065 -0.2794)
			(end -0.12065 -0.3048)
			(stroke
				(width 0.1)
				(type default)
			)
			(layer "B.Fab")
		)
		(fp_line
			(start -0.120396 0.2794)
			(end 0.12065 0.2794)
			(stroke
				(width 0.1)
				(type default)
			)
			(layer "B.Fab")
		)
		(fp_line
			(start -0.120396 0.3048)
			(end -0.120396 0.2794)
			(stroke
				(width 0.1)
				(type default)
			)
			(layer "B.Fab")
		)
		(fp_line
			(start 0.12065 -0.305054)
			(end 0.12065 -0.2794)
			(stroke
				(width 0.1)
				(type default)
			)
			(layer "B.Fab")
		)
		(fp_line
			(start 0.12065 -0.2794)
			(end -0.12065 -0.2794)
			(stroke
				(width 0.1)
				(type default)
			)
			(layer "B.Fab")
		)
		(fp_line
			(start 0.12065 0.2794)
			(end 0.12065 0.3048)
			(stroke
				(width 0.1)
				(type default)
			)
			(layer "B.Fab")
		)
		(fp_line
			(start 0.12065 0.3048)
			(end 0.67945 0.3048)
			(stroke
				(width 0.1)
				(type default)
			)
			(layer "B.Fab")
		)
		(fp_line
			(start 0.67945 -0.305054)
			(end 0.12065 -0.305054)
			(stroke
				(width 0.1)
				(type default)
			)
			(layer "B.Fab")
		)
		(fp_line
			(start 0.67945 0.3048)
			(end 0.67945 -0.305054)
			(stroke
				(width 0.1)
				(type default)
			)
			(layer "B.Fab")
		)
		(pad "1" smd circle
			(at 0.40005 0 180)
			(size 0 0)
			(layers "B.Cu" "B.Mask" "B.Paste")
			(net "M_G_CPU1_ALERT_N")
		)
		(pad "2" smd circle
			(at -0.40005 0 180)
			(size 0 0)
			(layers "B.Cu" "B.Mask" "B.Paste")
			(net "M_G_CPU1_ALERT_R_N")
		)
	)
	(footprint ""
		(layer "B.Cu")
		(at 448.38874 -397.05407 90)
		(property "Reference" "PC6557_1"
			(at 0 0 90)
			(layer "B.SilkS")
			(hide yes)
			(effects
				(font
					(size 1.27 1.27)
				)
				(justify mirror)
			)
		)
		(property "Value" ""
			(at 0 0 90)
			(layer "B.Fab")
			(effects
				(font
					(size 1.27 1.27)
				)
				(justify mirror)
			)
		)
		(duplicate_pad_numbers_are_jumpers no)
		(fp_line
			(start 1.524 -0.762)
			(end -1.524 -0.762)
			(stroke
				(width 0.1524)
				(type default)
			)
			(layer "B.SilkS")
		)
		(fp_line
			(start -1.524 -0.762)
			(end -1.524 0.762)
			(stroke
				(width 0.1524)
				(type default)
			)
			(layer "B.SilkS")
		)
		(fp_line
			(start 1.524 0.762)
			(end 1.524 -0.762)
			(stroke
				(width 0.1524)
				(type default)
			)
			(layer "B.SilkS")
		)
		(fp_line
			(start -1.524 0.762)
			(end 1.524 0.762)
			(stroke
				(width 0.1524)
				(type default)
			)
			(layer "B.SilkS")
		)
		(fp_line
			(start 1.1049 -0.724916)
			(end 1.1049 0.724916)
			(stroke
				(width 0.1)
				(type default)
			)
			(layer "B.Fab")
		)
		(fp_line
			(start -1.1049 -0.724916)
			(end 1.1049 -0.724916)
			(stroke
				(width 0.1)
				(type default)
			)
			(layer "B.Fab")
		)
		(fp_line
			(start 1.1049 0.724916)
			(end -1.1049 0.724916)
			(stroke
				(width 0.1)
				(type default)
			)
			(layer "B.Fab")
		)
		(fp_line
			(start -1.1049 0.724916)
			(end -1.1049 -0.724916)
			(stroke
				(width 0.1)
				(type default)
			)
			(layer "B.Fab")
		)
		(pad "1" smd rect
			(at 0.889 0 90)
			(size 1.016 1.27)
			(layers "B.Cu" "B.Mask" "B.Paste")
			(net "SW_P12V_AUX_P0V9_RETIMER_CPU0_FLT")
		)
		(pad "2" smd rect
			(at -0.889 0 90)
			(size 1.016 1.27)
			(layers "B.Cu" "B.Mask" "B.Paste")
			(net "GND")
		)
	)
	(footprint ""
		(layer "B.Cu")
		(at 415.712402 -194.88531 180)
		(property "Reference" "R1574"
			(at 0 0 0)
			(layer "B.SilkS")
			(hide yes)
			(effects
				(font
					(size 1.27 1.27)
				)
				(justify mirror)
			)
		)
		(property "Value" ""
			(at 0 0 0)
			(layer "B.Fab")
			(effects
				(font
					(size 1.27 1.27)
				)
				(justify mirror)
			)
		)
		(duplicate_pad_numbers_are_jumpers no)
		(fp_line
			(start 0.7874 0.4064)
			(end 0.7874 -0.4064)
			(stroke
				(width 0.1524)
				(type default)
			)
			(layer "B.SilkS")
		)
		(fp_line
			(start 0.7874 -0.4064)
			(end -0.7874 -0.4064)
			(stroke
				(width 0.1524)
				(type default)
			)
			(layer "B.SilkS")
		)
		(fp_line
			(start -0.7874 0.4064)
			(end 0.7874 0.4064)
			(stroke
				(width 0.1524)
				(type default)
			)
			(layer "B.SilkS")
		)
		(fp_line
			(start -0.7874 -0.4064)
			(end -0.7874 0.4064)
			(stroke
				(width 0.1524)
				(type default)
			)
			(layer "B.SilkS")
		)
		(fp_line
			(start 0.67945 0.3048)
			(end 0.67945 -0.305054)
			(stroke
				(width 0.1)
				(type default)
			)
			(layer "B.Fab")
		)
		(fp_line
			(start 0.67945 -0.305054)
			(end 0.12065 -0.305054)
			(stroke
				(width 0.1)
				(type default)
			)
			(layer "B.Fab")
		)
		(fp_line
			(start 0.12065 0.3048)
			(end 0.67945 0.3048)
			(stroke
				(width 0.1)
				(type default)
			)
			(layer "B.Fab")
		)
		(fp_line
			(start 0.12065 0.2794)
			(end 0.12065 0.3048)
			(stroke
				(width 0.1)
				(type default)
			)
			(layer "B.Fab")
		)
		(fp_line
			(start 0.12065 -0.2794)
			(end -0.12065 -0.2794)
			(stroke
				(width 0.1)
				(type default)
			)
			(layer "B.Fab")
		)
		(fp_line
			(start 0.12065 -0.305054)
			(end 0.12065 -0.2794)
			(stroke
				(width 0.1)
				(type default)
			)
			(layer "B.Fab")
		)
		(fp_line
			(start -0.120396 0.3048)
			(end -0.120396 0.2794)
			(stroke
				(width 0.1)
				(type default)
			)
			(layer "B.Fab")
		)
		(fp_line
			(start -0.120396 0.2794)
			(end 0.12065 0.2794)
			(stroke
				(width 0.1)
				(type default)
			)
			(layer "B.Fab")
		)
		(fp_line
			(start -0.12065 -0.2794)
			(end -0.12065 -0.3048)
			(stroke
				(width 0.1)
				(type default)
			)
			(layer "B.Fab")
		)
		(fp_line
			(start -0.12065 -0.3048)
			(end -0.67945 -0.3048)
			(stroke
				(width 0.1)
				(type default)
			)
			(layer "B.Fab")
		)
		(fp_line
			(start -0.67945 0.3048)
			(end -0.120396 0.3048)
			(stroke
				(width 0.1)
				(type default)
			)
			(layer "B.Fab")
		)
		(fp_line
			(start -0.67945 -0.3048)
			(end -0.67945 0.3048)
			(stroke
				(width 0.1)
				(type default)
			)
			(layer "B.Fab")
		)
		(pad "1" smd circle
			(at 0.40005 0)
			(size 0 0)
			(layers "B.Cu" "B.Mask" "B.Paste")
			(net "I3C_SPD_DDRGL_CPU0_SCL")
		)
		(pad "2" smd circle
			(at -0.40005 0)
			(size 0 0)
			(layers "B.Cu" "B.Mask" "B.Paste")
			(net "I3C_SPD_DDRG_CPU0_SCL")
		)
	)
	(footprint ""
		(layer "B.Cu")
		(at 430.80051 -194.88531 180)
		(property "Reference" "R1576"
			(at 0 0 0)
			(layer "B.SilkS")
			(hide yes)
			(effects
				(font
					(size 1.27 1.27)
				)
				(justify mirror)
			)
		)
		(property "Value" ""
			(at 0 0 0)
			(layer "B.Fab")
			(effects
				(font
					(size 1.27 1.27)
				)
				(justify mirror)
			)
		)
		(duplicate_pad_numbers_are_jumpers no)
		(fp_line
			(start 0.7874 0.4064)
			(end 0.7874 -0.4064)
			(stroke
				(width 0.1524)
				(type default)
			)
			(layer "B.SilkS")
		)
		(fp_line
			(start 0.7874 -0.4064)
			(end -0.7874 -0.4064)
			(stroke
				(width 0.1524)
				(type default)
			)
			(layer "B.SilkS")
		)
		(fp_line
			(start -0.7874 0.4064)
			(end 0.7874 0.4064)
			(stroke
				(width 0.1524)
				(type default)
			)
			(layer "B.SilkS")
		)
		(fp_line
			(start -0.7874 -0.4064)
			(end -0.7874 0.4064)
			(stroke
				(width 0.1524)
				(type default)
			)
			(layer "B.SilkS")
		)
		(fp_line
			(start 0.67945 0.3048)
			(end 0.67945 -0.305054)
			(stroke
				(width 0.1)
				(type default)
			)
			(layer "B.Fab")
		)
		(fp_line
			(start 0.67945 -0.305054)
			(end 0.12065 -0.305054)
			(stroke
				(width 0.1)
				(type default)
			)
			(layer "B.Fab")
		)
		(fp_line
			(start 0.12065 0.3048)
			(end 0.67945 0.3048)
			(stroke
				(width 0.1)
				(type default)
			)
			(layer "B.Fab")
		)
		(fp_line
			(start 0.12065 0.2794)
			(end 0.12065 0.3048)
			(stroke
				(width 0.1)
				(type default)
			)
			(layer "B.Fab")
		)
		(fp_line
			(start 0.12065 -0.2794)
			(end -0.12065 -0.2794)
			(stroke
				(width 0.1)
				(type default)
			)
			(layer "B.Fab")
		)
		(fp_line
			(start 0.12065 -0.305054)
			(end 0.12065 -0.2794)
			(stroke
				(width 0.1)
				(type default)
			)
			(layer "B.Fab")
		)
		(fp_line
			(start -0.120396 0.3048)
			(end -0.120396 0.2794)
			(stroke
				(width 0.1)
				(type default)
			)
			(layer "B.Fab")
		)
		(fp_line
			(start -0.120396 0.2794)
			(end 0.12065 0.2794)
			(stroke
				(width 0.1)
				(type default)
			)
			(layer "B.Fab")
		)
		(fp_line
			(start -0.12065 -0.2794)
			(end -0.12065 -0.3048)
			(stroke
				(width 0.1)
				(type default)
			)
			(layer "B.Fab")
		)
		(fp_line
			(start -0.12065 -0.3048)
			(end -0.67945 -0.3048)
			(stroke
				(width 0.1)
				(type default)
			)
			(layer "B.Fab")
		)
		(fp_line
			(start -0.67945 0.3048)
			(end -0.120396 0.3048)
			(stroke
				(width 0.1)
				(type default)
			)
			(layer "B.Fab")
		)
		(fp_line
			(start -0.67945 -0.3048)
			(end -0.67945 0.3048)
			(stroke
				(width 0.1)
				(type default)
			)
			(layer "B.Fab")
		)
		(pad "1" smd circle
			(at 0.40005 0)
			(size 0 0)
			(layers "B.Cu" "B.Mask" "B.Paste")
			(net "I3C_SPD_DDRGL_CPU0_SCL")
		)
		(pad "2" smd circle
			(at -0.40005 0)
			(size 0 0)
			(layers "B.Cu" "B.Mask" "B.Paste")
			(net "I3C_SPD_DDRI_CPU0_SCL")
		)
	)
	(footprint ""
		(layer "B.Cu")
		(at 188.071506 -126.833376 -90)
		(property "Reference" "R1558"
			(at 0 0 90)
			(layer "B.SilkS")
			(hide yes)
			(effects
				(font
					(size 1.27 1.27)
				)
				(justify mirror)
			)
		)
		(property "Value" ""
			(at 0 0 90)
			(layer "B.Fab")
			(effects
				(font
					(size 1.27 1.27)
				)
				(justify mirror)
			)
		)
		(duplicate_pad_numbers_are_jumpers no)
		(fp_line
			(start -0.7874 0.4064)
			(end 0.7874 0.4064)
			(stroke
				(width 0.1524)
				(type default)
			)
			(layer "B.SilkS")
		)
		(fp_line
			(start 0.7874 0.4064)
			(end 0.7874 -0.4064)
			(stroke
				(width 0.1524)
				(type default)
			)
			(layer "B.SilkS")
		)
		(fp_line
			(start -0.7874 -0.4064)
			(end -0.7874 0.4064)
			(stroke
				(width 0.1524)
				(type default)
			)
			(layer "B.SilkS")
		)
		(fp_line
			(start 0.7874 -0.4064)
			(end -0.7874 -0.4064)
			(stroke
				(width 0.1524)
				(type default)
			)
			(layer "B.SilkS")
		)
		(fp_line
			(start -0.67945 0.3048)
			(end -0.120396 0.3048)
			(stroke
				(width 0.1)
				(type default)
			)
			(layer "B.Fab")
		)
		(fp_line
			(start -0.120396 0.3048)
			(end -0.120396 0.2794)
			(stroke
				(width 0.1)
				(type default)
			)
			(layer "B.Fab")
		)
		(fp_line
			(start 0.12065 0.3048)
			(end 0.67945 0.3048)
			(stroke
				(width 0.1)
				(type default)
			)
			(layer "B.Fab")
		)
		(fp_line
			(start 0.67945 0.3048)
			(end 0.67945 -0.305054)
			(stroke
				(width 0.1)
				(type default)
			)
			(layer "B.Fab")
		)
		(fp_line
			(start -0.120396 0.2794)
			(end 0.12065 0.2794)
			(stroke
				(width 0.1)
				(type default)
			)
			(layer "B.Fab")
		)
		(fp_line
			(start 0.12065 0.2794)
			(end 0.12065 0.3048)
			(stroke
				(width 0.1)
				(type default)
			)
			(layer "B.Fab")
		)
		(fp_line
			(start -0.12065 -0.2794)
			(end -0.12065 -0.3048)
			(stroke
				(width 0.1)
				(type default)
			)
			(layer "B.Fab")
		)
		(fp_line
			(start 0.12065 -0.2794)
			(end -0.12065 -0.2794)
			(stroke
				(width 0.1)
				(type default)
			)
			(layer "B.Fab")
		)
		(fp_line
			(start -0.67945 -0.3048)
			(end -0.67945 0.3048)
			(stroke
				(width 0.1)
				(type default)
			)
			(layer "B.Fab")
		)
		(fp_line
			(start -0.12065 -0.3048)
			(end -0.67945 -0.3048)
			(stroke
				(width 0.1)
				(type default)
			)
			(layer "B.Fab")
		)
		(fp_line
			(start 0.12065 -0.305054)
			(end 0.12065 -0.2794)
			(stroke
				(width 0.1)
				(type default)
			)
			(layer "B.Fab")
		)
		(fp_line
			(start 0.67945 -0.305054)
			(end 0.12065 -0.305054)
			(stroke
				(width 0.1)
				(type default)
			)
			(layer "B.Fab")
		)
		(pad "1" smd circle
			(at 0.40005 0 90)
			(size 0 0)
			(layers "B.Cu" "B.Mask" "B.Paste")
			(net "RST_ESPI_CPU0_RSTOUT_R_N")
		)
		(pad "2" smd circle
			(at -0.40005 0 90)
			(size 0 0)
			(layers "B.Cu" "B.Mask" "B.Paste")
			(net "RST_ESPI_CPU0_RSTOUT_N")
		)
	)
	(footprint ""
		(layer "B.Cu")
		(at 288.935668 -193.99631)
		(property "Reference" "R91"
			(at 0 0 0)
			(layer "B.SilkS")
			(hide yes)
			(effects
				(font
					(size 1.27 1.27)
				)
				(justify mirror)
			)
		)
		(property "Value" ""
			(at 0 0 0)
			(layer "B.Fab")
			(effects
				(font
					(size 1.27 1.27)
				)
				(justify mirror)
			)
		)
		(duplicate_pad_numbers_are_jumpers no)
		(fp_line
			(start -0.7874 -0.4064)
			(end -0.7874 0.4064)
			(stroke
				(width 0.1524)
				(type default)
			)
			(layer "B.SilkS")
		)
		(fp_line
			(start -0.7874 0.4064)
			(end 0.7874 0.4064)
			(stroke
				(width 0.1524)
				(type default)
			)
			(layer "B.SilkS")
		)
		(fp_line
			(start 0.7874 -0.4064)
			(end -0.7874 -0.4064)
			(stroke
				(width 0.1524)
				(type default)
			)
			(layer "B.SilkS")
		)
		(fp_line
			(start 0.7874 0.4064)
			(end 0.7874 -0.4064)
			(stroke
				(width 0.1524)
				(type default)
			)
			(layer "B.SilkS")
		)
		(fp_line
			(start -0.67945 -0.3048)
			(end -0.67945 0.3048)
			(stroke
				(width 0.1)
				(type default)
			)
			(layer "B.Fab")
		)
		(fp_line
			(start -0.67945 0.3048)
			(end -0.120396 0.3048)
			(stroke
				(width 0.1)
				(type default)
			)
			(layer "B.Fab")
		)
		(fp_line
			(start -0.12065 -0.3048)
			(end -0.67945 -0.3048)
			(stroke
				(width 0.1)
				(type default)
			)
			(layer "B.Fab")
		)
		(fp_line
			(start -0.12065 -0.2794)
			(end -0.12065 -0.3048)
			(stroke
				(width 0.1)
				(type default)
			)
			(layer "B.Fab")
		)
		(fp_line
			(start -0.120396 0.2794)
			(end 0.12065 0.2794)
			(stroke
				(width 0.1)
				(type default)
			)
			(layer "B.Fab")
		)
		(fp_line
			(start -0.120396 0.3048)
			(end -0.120396 0.2794)
			(stroke
				(width 0.1)
				(type default)
			)
			(layer "B.Fab")
		)
		(fp_line
			(start 0.12065 -0.305054)
			(end 0.12065 -0.2794)
			(stroke
				(width 0.1)
				(type default)
			)
			(layer "B.Fab")
		)
		(fp_line
			(start 0.12065 -0.2794)
			(end -0.12065 -0.2794)
			(stroke
				(width 0.1)
				(type default)
			)
			(layer "B.Fab")
		)
		(fp_line
			(start 0.12065 0.2794)
			(end 0.12065 0.3048)
			(stroke
				(width 0.1)
				(type default)
			)
			(layer "B.Fab")
		)
		(fp_line
			(start 0.12065 0.3048)
			(end 0.67945 0.3048)
			(stroke
				(width 0.1)
				(type default)
			)
			(layer "B.Fab")
		)
		(fp_line
			(start 0.67945 -0.305054)
			(end 0.12065 -0.305054)
			(stroke
				(width 0.1)
				(type default)
			)
			(layer "B.Fab")
		)
		(fp_line
			(start 0.67945 0.3048)
			(end 0.67945 -0.305054)
			(stroke
				(width 0.1)
				(type default)
			)
			(layer "B.Fab")
		)
		(pad "1" smd circle
			(at 0.40005 0 180)
			(size 0 0)
			(layers "B.Cu" "B.Mask" "B.Paste")
			(net "P3V3")
		)
		(pad "2" smd circle
			(at -0.40005 0 180)
			(size 0 0)
			(layers "B.Cu" "B.Mask" "B.Paste")
			(net "PWRGD_CHC_CPU0_DIMM")
		)
	)
)
